(kicad_pcb
	(version 20241229)
	(generator "pcbnew")
	(generator_version "9.0")
	(general
		(thickness 1.61)
		(legacy_teardrops no)
	)
	(paper "A3")
	(title_block
		(title "RDIMM DDR5 Tester")
		(date "2026-05-21")
		(rev "2.2.0")
		(company "Antmicro")
		(comment 9 "footprints 412-417 of 796")
	)
	(layers
		(0 "F.Cu" signal)
		(4 "In1.Cu" power)
		(6 "In2.Cu" mixed)
		(8 "In3.Cu" power)
		(10 "In4.Cu" mixed)
		(12 "In5.Cu" power)
		(14 "In6.Cu" mixed)
		(16 "In7.Cu" power)
		(18 "In8.Cu" power)
		(20 "In9.Cu" mixed)
		(22 "In10.Cu" power)
		(2 "B.Cu" signal)
		(9 "F.Adhes" user "F.Adhesive")
		(11 "B.Adhes" user "B.Adhesive")
		(13 "F.Paste" user)
		(15 "B.Paste" user)
		(5 "F.SilkS" user "F.Silkscreen")
		(7 "B.SilkS" user "B.Silkscreen")
		(1 "F.Mask" user)
		(3 "B.Mask" user)
		(17 "Dwgs.User" user "User.Drawings")
		(19 "Cmts.User" user "User.Comments")
		(21 "Eco1.User" user "User.Eco1")
		(23 "Eco2.User" user "User.Eco2")
		(25 "Edge.Cuts" user)
		(27 "Margin" user)
		(31 "F.CrtYd" user "F.Courtyard")
		(29 "B.CrtYd" user "B.Courtyard")
		(35 "F.Fab" user)
		(33 "B.Fab" user)
	)
	(footprint "antmicro-footprints:R_0402_1005Metric"
		(layer "B.Cu")
		(at 106.874499 128.749 90)
		(descr "Resistor SMD 0402")
		(tags "resistor SMD 0402")
		(property "Reference" "R98"
			(at 1.495 0.313501 90)
			(layer "B.SilkS")
			(effects
				(font
					(size 0.7 0.7)
					(thickness 0.15)
				)
				(justify right bottom mirror)
			)
		)
		(property "Value" "R_220R_0402"
			(at -1.011843 -1.772047 90)
			(layer "B.Fab")
			(effects
				(font
					(size 0.7 0.7)
					(thickness 0.15)
				)
				(justify right bottom mirror)
			)
		)
		(property "Datasheet" "https://www.bourns.com/docs/product-datasheets/cr.pdf"
			(at 0 0 90)
			(layer "F.Fab")
			(hide yes)
			(effects
				(font
					(size 1.27 1.27)
					(thickness 0.15)
				)
			)
		)
		(property "Manufacturer" "Bourns"
			(at 0 0 90)
			(unlocked yes)
			(layer "B.Fab")
			(hide yes)
			(effects
				(font
					(size 1 1)
					(thickness 0.15)
				)
				(justify mirror)
			)
		)
		(property "MPN" "CR0402-FX-2200GLF"
			(at 0 0 90)
			(unlocked yes)
			(layer "B.Fab")
			(hide yes)
			(effects
				(font
					(size 1 1)
					(thickness 0.15)
				)
				(justify mirror)
			)
		)
		(property "Val" "220R"
			(at 0 0 90)
			(unlocked yes)
			(layer "B.Fab")
			(hide yes)
			(effects
				(font
					(size 1 1)
					(thickness 0.15)
				)
				(justify mirror)
			)
		)
		(property "License" "Apache-2.0"
			(at 0 0 90)
			(unlocked yes)
			(layer "B.Fab")
			(hide yes)
			(effects
				(font
					(size 1 1)
					(thickness 0.15)
				)
				(justify mirror)
			)
		)
		(property "Author" "Antmicro"
			(at 0 0 90)
			(unlocked yes)
			(layer "B.Fab")
			(hide yes)
			(effects
				(font
					(size 1 1)
					(thickness 0.15)
				)
				(justify mirror)
			)
		)
		(property "Tolerance" "1%"
			(at 0 0 90)
			(unlocked yes)
			(layer "B.Fab")
			(hide yes)
			(effects
				(font
					(size 1 1)
					(thickness 0.15)
				)
				(justify mirror)
			)
		)
		(sheetname "/Ethernet/")
		(sheetfile "ethernet.kicad_sch")
		(attr smd)
		(fp_rect
			(start -0.925 0.47)
			(end 0.925 -0.47)
			(stroke
				(width 0.05)
				(type default)
			)
			(fill no)
			(layer "B.CrtYd")
		)
		(fp_rect
			(start -0.5 0.25)
			(end 0.5 -0.25)
			(stroke
				(width 0.15)
				(type solid)
			)
			(fill no)
			(layer "B.Fab")
		)
		(fp_text user "Author: Antmicro"
			(at -0.95 -4.169 270)
			(layer "B.Fab")
			(effects
				(font
					(size 0.7 0.7)
					(thickness 0.15)
				)
				(justify left bottom mirror)
			)
		)
		(fp_text user "License: Apache-2.0"
			(at -0.95 -5.169 270)
			(layer "B.Fab")
			(effects
				(font
					(size 0.7 0.7)
					(thickness 0.15)
				)
				(justify left bottom mirror)
			)
		)
		(fp_text user "${REFERENCE}"
			(at -0.95 -3.168 270)
			(layer "B.Fab")
			(effects
				(font
					(size 0.7 0.7)
					(thickness 0.15)
				)
				(justify left bottom mirror)
			)
		)
		(pad "1" smd roundrect
			(at -0.48 0 90)
			(size 0.59 0.64)
			(layers "B.Cu" "B.Mask" "B.Paste")
			(roundrect_rratio 0.25)
			(net 824 "Net-(J6-LED_Y+)")
			(pintype "passive")
		)
		(pad "2" smd roundrect
			(at 0.48 0 90)
			(size 0.59 0.64)
			(layers "B.Cu" "B.Mask" "B.Paste")
			(roundrect_rratio 0.25)
			(net 151 "+3V3")
			(pintype "passive")
		)
	)
	(footprint "antmicro-footprints:R_0402_1005Metric"
		(layer "B.Cu")
		(at 106.895 122.335 -90)
		(descr "Resistor SMD 0402")
		(tags "resistor SMD 0402")
		(property "Reference" "R99"
			(at -3.209 -0.293 90)
			(layer "B.SilkS")
			(effects
				(font
					(size 0.7 0.7)
					(thickness 0.15)
				)
				(justify left bottom mirror)
			)
		)
		(property "Value" "R_220R_0402"
			(at -1.011843 -1.772047 90)
			(layer "B.Fab")
			(effects
				(font
					(size 0.7 0.7)
					(thickness 0.15)
				)
				(justify left bottom mirror)
			)
		)
		(property "Datasheet" "https://www.bourns.com/docs/product-datasheets/cr.pdf"
			(at 0 0 270)
			(layer "F.Fab")
			(hide yes)
			(effects
				(font
					(size 1.27 1.27)
					(thickness 0.15)
				)
			)
		)
		(property "Manufacturer" "Bourns"
			(at 0 0 270)
			(unlocked yes)
			(layer "B.Fab")
			(hide yes)
			(effects
				(font
					(size 1 1)
					(thickness 0.15)
				)
				(justify mirror)
			)
		)
		(property "MPN" "CR0402-FX-2200GLF"
			(at 0 0 270)
			(unlocked yes)
			(layer "B.Fab")
			(hide yes)
			(effects
				(font
					(size 1 1)
					(thickness 0.15)
				)
				(justify mirror)
			)
		)
		(property "Val" "220R"
			(at 0 0 270)
			(unlocked yes)
			(layer "B.Fab")
			(hide yes)
			(effects
				(font
					(size 1 1)
					(thickness 0.15)
				)
				(justify mirror)
			)
		)
		(property "License" "Apache-2.0"
			(at 0 0 270)
			(unlocked yes)
			(layer "B.Fab")
			(hide yes)
			(effects
				(font
					(size 1 1)
					(thickness 0.15)
				)
				(justify mirror)
			)
		)
		(property "Author" "Antmicro"
			(at 0 0 270)
			(unlocked yes)
			(layer "B.Fab")
			(hide yes)
			(effects
				(font
					(size 1 1)
					(thickness 0.15)
				)
				(justify mirror)
			)
		)
		(property "Tolerance" "1%"
			(at 0 0 270)
			(unlocked yes)
			(layer "B.Fab")
			(hide yes)
			(effects
				(font
					(size 1 1)
					(thickness 0.15)
				)
				(justify mirror)
			)
		)
		(sheetname "/Ethernet/")
		(sheetfile "ethernet.kicad_sch")
		(attr smd)
		(fp_rect
			(start -0.925 0.47)
			(end 0.925 -0.47)
			(stroke
				(width 0.05)
				(type default)
			)
			(fill no)
			(layer "B.CrtYd")
		)
		(fp_rect
			(start -0.5 0.25)
			(end 0.5 -0.25)
			(stroke
				(width 0.15)
				(type solid)
			)
			(fill no)
			(layer "B.Fab")
		)
		(fp_text user "${REFERENCE}"
			(at -0.95 -3.168 90)
			(layer "B.Fab")
			(effects
				(font
					(size 0.7 0.7)
					(thickness 0.15)
				)
				(justify left bottom mirror)
			)
		)
		(fp_text user "License: Apache-2.0"
			(at -0.95 -5.169 90)
			(layer "B.Fab")
			(effects
				(font
					(size 0.7 0.7)
					(thickness 0.15)
				)
				(justify left bottom mirror)
			)
		)
		(fp_text user "Author: Antmicro"
			(at -0.95 -4.169 90)
			(layer "B.Fab")
			(effects
				(font
					(size 0.7 0.7)
					(thickness 0.15)
				)
				(justify left bottom mirror)
			)
		)
		(pad "1" smd roundrect
			(at -0.48 0 270)
			(size 0.59 0.64)
			(layers "B.Cu" "B.Mask" "B.Paste")
			(roundrect_rratio 0.25)
			(net 823 "Net-(J6-LED_G+)")
			(pintype "passive")
		)
		(pad "2" smd roundrect
			(at 0.48 0 270)
			(size 0.59 0.64)
			(layers "B.Cu" "B.Mask" "B.Paste")
			(roundrect_rratio 0.25)
			(net 151 "+3V3")
			(pintype "passive")
		)
	)
	(footprint "antmicro-footprints:R_0402_1005Metric"
		(layer "B.Cu")
		(at 140.65 152.4 -90)
		(descr "Resistor SMD 0402")
		(tags "resistor SMD 0402")
		(property "Reference" "R113"
			(at 8 -0.375 90)
			(layer "B.SilkS")
			(effects
				(font
					(size 0.7 0.7)
					(thickness 0.15)
				)
				(justify left bottom mirror)
			)
		)
		(property "Value" "R_2k2_0402"
			(at -1.011843 -1.772047 90)
			(layer "B.Fab")
			(effects
				(font
					(size 0.7 0.7)
					(thickness 0.15)
				)
				(justify left bottom mirror)
			)
		)
		(property "Datasheet" "https://www.bourns.com/docs/product-datasheets/cr.pdf"
			(at 0 0 270)
			(layer "F.Fab")
			(hide yes)
			(effects
				(font
					(size 1.27 1.27)
					(thickness 0.15)
				)
			)
		)
		(property "Manufacturer" "Bourns"
			(at 0 0 270)
			(unlocked yes)
			(layer "B.Fab")
			(hide yes)
			(effects
				(font
					(size 1 1)
					(thickness 0.15)
				)
				(justify mirror)
			)
		)
		(property "MPN" "CR0402-FX-2201GLF"
			(at 0 0 270)
			(unlocked yes)
			(layer "B.Fab")
			(hide yes)
			(effects
				(font
					(size 1 1)
					(thickness 0.15)
				)
				(justify mirror)
			)
		)
		(property "Val" "2k2"
			(at 0 0 270)
			(unlocked yes)
			(layer "B.Fab")
			(hide yes)
			(effects
				(font
					(size 1 1)
					(thickness 0.15)
				)
				(justify mirror)
			)
		)
		(property "License" "Apache-2.0"
			(at 0 0 270)
			(unlocked yes)
			(layer "B.Fab")
			(hide yes)
			(effects
				(font
					(size 1 1)
					(thickness 0.15)
				)
				(justify mirror)
			)
		)
		(property "Author" "Antmicro"
			(at 0 0 270)
			(unlocked yes)
			(layer "B.Fab")
			(hide yes)
			(effects
				(font
					(size 1 1)
					(thickness 0.15)
				)
				(justify mirror)
			)
		)
		(property "Tolerance" "1%"
			(at 0 0 270)
			(unlocked yes)
			(layer "B.Fab")
			(hide yes)
			(effects
				(font
					(size 1 1)
					(thickness 0.15)
				)
				(justify mirror)
			)
		)
		(sheetname "/Ethernet/")
		(sheetfile "ethernet.kicad_sch")
		(attr smd)
		(fp_rect
			(start -0.925 0.47)
			(end 0.925 -0.47)
			(stroke
				(width 0.05)
				(type default)
			)
			(fill no)
			(layer "B.CrtYd")
		)
		(fp_rect
			(start -0.5 0.25)
			(end 0.5 -0.25)
			(stroke
				(width 0.15)
				(type solid)
			)
			(fill no)
			(layer "B.Fab")
		)
		(fp_text user "Author: Antmicro"
			(at -0.95 -4.169 90)
			(layer "B.Fab")
			(effects
				(font
					(size 0.7 0.7)
					(thickness 0.15)
				)
				(justify left bottom mirror)
			)
		)
		(fp_text user "License: Apache-2.0"
			(at -0.95 -5.169 90)
			(layer "B.Fab")
			(effects
				(font
					(size 0.7 0.7)
					(thickness 0.15)
				)
				(justify left bottom mirror)
			)
		)
		(fp_text user "${REFERENCE}"
			(at -0.95 -3.168 90)
			(layer "B.Fab")
			(effects
				(font
					(size 0.7 0.7)
					(thickness 0.15)
				)
				(justify left bottom mirror)
			)
		)
		(pad "1" smd roundrect
			(at -0.48 0 270)
			(size 0.59 0.64)
			(layers "B.Cu" "B.Mask" "B.Paste")
			(roundrect_rratio 0.25)
			(net 393 "/Ethernet/ETH.RXD0")
			(pintype "passive")
		)
		(pad "2" smd roundrect
			(at 0.48 0 270)
			(size 0.59 0.64)
			(layers "B.Cu" "B.Mask" "B.Paste")
			(roundrect_rratio 0.25)
			(net 1 "GND")
			(pintype "passive")
		)
	)
	(footprint "antmicro-footprints:R_0402_1005Metric"
		(layer "B.Cu")
		(at 139.22 148.17 180)
		(descr "Resistor SMD 0402")
		(tags "resistor SMD 0402")
		(property "Reference" "R110"
			(at -3.62 -0.46 0)
			(layer "B.SilkS")
			(effects
				(font
					(size 0.7 0.7)
					(thickness 0.15)
				)
				(justify left bottom mirror)
			)
		)
		(property "Value" "R_1k_0402"
			(at -1.011843 -1.772047 0)
			(layer "B.Fab")
			(effects
				(font
					(size 0.7 0.7)
					(thickness 0.15)
				)
				(justify left bottom mirror)
			)
		)
		(property "Datasheet" "https://www.bourns.com/docs/product-datasheets/cr.pdf"
			(at 0 0 180)
			(layer "F.Fab")
			(hide yes)
			(effects
				(font
					(size 1.27 1.27)
					(thickness 0.15)
				)
			)
		)
		(property "Manufacturer" "Bourns"
			(at 0 0 180)
			(unlocked yes)
			(layer "B.Fab")
			(hide yes)
			(effects
				(font
					(size 1 1)
					(thickness 0.15)
				)
				(justify mirror)
			)
		)
		(property "MPN" "CR0402-FX-1001GLF"
			(at 0 0 180)
			(unlocked yes)
			(layer "B.Fab")
			(hide yes)
			(effects
				(font
					(size 1 1)
					(thickness 0.15)
				)
				(justify mirror)
			)
		)
		(property "Val" "1k"
			(at 0 0 180)
			(unlocked yes)
			(layer "B.Fab")
			(hide yes)
			(effects
				(font
					(size 1 1)
					(thickness 0.15)
				)
				(justify mirror)
			)
		)
		(property "License" "Apache-2.0"
			(at 0 0 180)
			(unlocked yes)
			(layer "B.Fab")
			(hide yes)
			(effects
				(font
					(size 1 1)
					(thickness 0.15)
				)
				(justify mirror)
			)
		)
		(property "Author" "Antmicro"
			(at 0 0 180)
			(unlocked yes)
			(layer "B.Fab")
			(hide yes)
			(effects
				(font
					(size 1 1)
					(thickness 0.15)
				)
				(justify mirror)
			)
		)
		(property "Tolerance" "1%"
			(at 0 0 180)
			(unlocked yes)
			(layer "B.Fab")
			(hide yes)
			(effects
				(font
					(size 1 1)
					(thickness 0.15)
				)
				(justify mirror)
			)
		)
		(sheetname "/Ethernet/")
		(sheetfile "ethernet.kicad_sch")
		(attr smd)
		(fp_rect
			(start -0.925 0.47)
			(end 0.925 -0.47)
			(stroke
				(width 0.05)
				(type default)
			)
			(fill no)
			(layer "B.CrtYd")
		)
		(fp_rect
			(start -0.5 0.25)
			(end 0.5 -0.25)
			(stroke
				(width 0.15)
				(type solid)
			)
			(fill no)
			(layer "B.Fab")
		)
		(fp_text user "${REFERENCE}"
			(at -0.95 -3.168 0)
			(layer "B.Fab")
			(effects
				(font
					(size 0.7 0.7)
					(thickness 0.15)
				)
				(justify left bottom mirror)
			)
		)
		(fp_text user "Author: Antmicro"
			(at -0.95 -4.169 0)
			(layer "B.Fab")
			(effects
				(font
					(size 0.7 0.7)
					(thickness 0.15)
				)
				(justify left bottom mirror)
			)
		)
		(fp_text user "License: Apache-2.0"
			(at -0.95 -5.169 0)
			(layer "B.Fab")
			(effects
				(font
					(size 0.7 0.7)
					(thickness 0.15)
				)
				(justify left bottom mirror)
			)
		)
		(pad "1" smd roundrect
			(at -0.48 0 180)
			(size 0.59 0.64)
			(layers "B.Cu" "B.Mask" "B.Paste")
			(roundrect_rratio 0.25)
			(net 400 "/Ethernet/ETH.MDIO")
			(pintype "passive")
		)
		(pad "2" smd roundrect
			(at 0.48 0 180)
			(size 0.59 0.64)
			(layers "B.Cu" "B.Mask" "B.Paste")
			(roundrect_rratio 0.25)
			(net 797 "+1V8")
			(pintype "passive")
		)
	)
	(footprint "antmicro-footprints:R_0402_1005Metric"
		(layer "B.Cu")
		(at 138.55 152.4 -90)
		(descr "Resistor SMD 0402")
		(tags "resistor SMD 0402")
		(property "Reference" "R115"
			(at 8 -0.375 90)
			(layer "B.SilkS")
			(effects
				(font
					(size 0.7 0.7)
					(thickness 0.15)
				)
				(justify left bottom mirror)
			)
		)
		(property "Value" "R_2k2_0402"
			(at -1.011843 -1.772047 90)
			(layer "B.Fab")
			(effects
				(font
					(size 0.7 0.7)
					(thickness 0.15)
				)
				(justify left bottom mirror)
			)
		)
		(property "Datasheet" "https://www.bourns.com/docs/product-datasheets/cr.pdf"
			(at 0 0 270)
			(layer "F.Fab")
			(hide yes)
			(effects
				(font
					(size 1.27 1.27)
					(thickness 0.15)
				)
			)
		)
		(property "Manufacturer" "Bourns"
			(at 0 0 270)
			(unlocked yes)
			(layer "B.Fab")
			(hide yes)
			(effects
				(font
					(size 1 1)
					(thickness 0.15)
				)
				(justify mirror)
			)
		)
		(property "MPN" "CR0402-FX-2201GLF"
			(at 0 0 270)
			(unlocked yes)
			(layer "B.Fab")
			(hide yes)
			(effects
				(font
					(size 1 1)
					(thickness 0.15)
				)
				(justify mirror)
			)
		)
		(property "Val" "2k2"
			(at 0 0 270)
			(unlocked yes)
			(layer "B.Fab")
			(hide yes)
			(effects
				(font
					(size 1 1)
					(thickness 0.15)
				)
				(justify mirror)
			)
		)
		(property "License" "Apache-2.0"
			(at 0 0 270)
			(unlocked yes)
			(layer "B.Fab")
			(hide yes)
			(effects
				(font
					(size 1 1)
					(thickness 0.15)
				)
				(justify mirror)
			)
		)
		(property "Author" "Antmicro"
			(at 0 0 270)
			(unlocked yes)
			(layer "B.Fab")
			(hide yes)
			(effects
				(font
					(size 1 1)
					(thickness 0.15)
				)
				(justify mirror)
			)
		)
		(property "Tolerance" "1%"
			(at 0 0 270)
			(unlocked yes)
			(layer "B.Fab")
			(hide yes)
			(effects
				(font
					(size 1 1)
					(thickness 0.15)
				)
				(justify mirror)
			)
		)
		(sheetname "/Ethernet/")
		(sheetfile "ethernet.kicad_sch")
		(attr smd exclude_from_bom dnp)
		(fp_rect
			(start -0.925 0.47)
			(end 0.925 -0.47)
			(stroke
				(width 0.05)
				(type default)
			)
			(fill no)
			(layer "B.CrtYd")
		)
		(fp_rect
			(start -0.5 0.25)
			(end 0.5 -0.25)
			(stroke
				(width 0.15)
				(type solid)
			)
			(fill no)
			(layer "B.Fab")
		)
		(fp_text user "License: Apache-2.0"
			(at -0.95 -5.169 90)
			(layer "B.Fab")
			(effects
				(font
					(size 0.7 0.7)
					(thickness 0.15)
				)
				(justify left bottom mirror)
			)
		)
		(fp_text user "${REFERENCE}"
			(at -0.95 -3.168 90)
			(layer "B.Fab")
			(effects
				(font
					(size 0.7 0.7)
					(thickness 0.15)
				)
				(justify left bottom mirror)
			)
		)
		(fp_text user "Author: Antmicro"
			(at -0.95 -4.169 90)
			(layer "B.Fab")
			(effects
				(font
					(size 0.7 0.7)
					(thickness 0.15)
				)
				(justify left bottom mirror)
			)
		)
		(pad "1" smd roundrect
			(at -0.48 0 270)
			(size 0.59 0.64)
			(layers "B.Cu" "B.Mask" "B.Paste")
			(roundrect_rratio 0.25)
			(net 395 "/Ethernet/ETH.RXD2")
			(pintype "passive")
		)
		(pad "2" smd roundrect
			(at 0.48 0 270)
			(size 0.59 0.64)
			(layers "B.Cu" "B.Mask" "B.Paste")
			(roundrect_rratio 0.25)
			(net 1 "GND")
			(pintype "passive")
		)
	)
	(footprint "antmicro-footprints:R_0402_1005Metric"
		(layer "B.Cu")
		(at 142.75 152.4 -90)
		(descr "Resistor SMD 0402")
		(tags "resistor SMD 0402")
		(property "Reference" "R117"
			(at 8 -0.375 90)
			(layer "B.SilkS")
			(effects
				(font
					(size 0.7 0.7)
					(thickness 0.15)
				)
				(justify left bottom mirror)
			)
		)
		(property "Value" "R_2k2_0402"
			(at -1.011843 -1.772047 90)
			(layer "B.Fab")
			(effects
				(font
					(size 0.7 0.7)
					(thickness 0.15)
				)
				(justify left bottom mirror)
			)
		)
		(property "Datasheet" "https://www.bourns.com/docs/product-datasheets/cr.pdf"
			(at 0 0 270)
			(layer "F.Fab")
			(hide yes)
			(effects
				(font
					(size 1.27 1.27)
					(thickness 0.15)
				)
			)
		)
		(property "Manufacturer" "Bourns"
			(at 0 0 270)
			(unlocked yes)
			(layer "B.Fab")
			(hide yes)
			(effects
				(font
					(size 1 1)
					(thickness 0.15)
				)
				(justify mirror)
			)
		)
		(property "MPN" "CR0402-FX-2201GLF"
			(at 0 0 270)
			(unlocked yes)
			(layer "B.Fab")
			(hide yes)
			(effects
				(font
					(size 1 1)
					(thickness 0.15)
				)
				(justify mirror)
			)
		)
		(property "Val" "2k2"
			(at 0 0 270)
			(unlocked yes)
			(layer "B.Fab")
			(hide yes)
			(effects
				(font
					(size 1 1)
					(thickness 0.15)
				)
				(justify mirror)
			)
		)
		(property "License" "Apache-2.0"
			(at 0 0 270)
			(unlocked yes)
			(layer "B.Fab")
			(hide yes)
			(effects
				(font
					(size 1 1)
					(thickness 0.15)
				)
				(justify mirror)
			)
		)
		(property "Author" "Antmicro"
			(at 0 0 270)
			(unlocked yes)
			(layer "B.Fab")
			(hide yes)
			(effects
				(font
					(size 1 1)
					(thickness 0.15)
				)
				(justify mirror)
			)
		)
		(property "Tolerance" "1%"
			(at 0 0 270)
			(unlocked yes)
			(layer "B.Fab")
			(hide yes)
			(effects
				(font
					(size 1 1)
					(thickness 0.15)
				)
				(justify mirror)
			)
		)
		(sheetname "/Ethernet/")
		(sheetfile "ethernet.kicad_sch")
		(attr smd)
		(fp_rect
			(start -0.925 0.47)
			(end 0.925 -0.47)
			(stroke
				(width 0.05)
				(type default)
			)
			(fill no)
			(layer "B.CrtYd")
		)
		(fp_rect
			(start -0.5 0.25)
			(end 0.5 -0.25)
			(stroke
				(width 0.15)
				(type solid)
			)
			(fill no)
			(layer "B.Fab")
		)
		(fp_text user "Author: Antmicro"
			(at -0.95 -4.169 90)
			(layer "B.Fab")
			(effects
				(font
					(size 0.7 0.7)
					(thickness 0.15)
				)
				(justify left bottom mirror)
			)
		)
		(fp_text user "License: Apache-2.0"
			(at -0.95 -5.169 90)
			(layer "B.Fab")
			(effects
				(font
					(size 0.7 0.7)
					(thickness 0.15)
				)
				(justify left bottom mirror)
			)
		)
		(fp_text user "${REFERENCE}"
			(at -0.95 -3.168 90)
			(layer "B.Fab")
			(effects
				(font
					(size 0.7 0.7)
					(thickness 0.15)
				)
				(justify left bottom mirror)
			)
		)
		(pad "1" smd roundrect
			(at -0.48 0 270)
			(size 0.59 0.64)
			(layers "B.Cu" "B.Mask" "B.Paste")
			(roundrect_rratio 0.25)
			(net 397 "/Ethernet/ETH.RX_CTL")
			(pintype "passive")
		)
		(pad "2" smd roundrect
			(at 0.48 0 270)
			(size 0.59 0.64)
			(layers "B.Cu" "B.Mask" "B.Paste")
			(roundrect_rratio 0.25)
			(net 1 "GND")
			(pintype "passive")
		)
	)
)
